(kicad_pcb
	(version 20260206)
	(generator "pcbnew")
	(generator_version "10.0")
	(general
		(thickness 1.6)
		(legacy_teardrops no)
	)
	(paper "A4")
	(title_block
		(title "Bryce Canyon_F.DPB_16315-1-OCP.brd")
		(comment 1 "Bryce Canyon / footprints 1139-1144 of 2223")
	)
	(layers
		(0 "F.Cu" signal "TOP")
		(4 "In1.Cu" signal "L2GND")
		(6 "In2.Cu" signal "L3")
		(8 "In3.Cu" signal "L4GND")
		(10 "In4.Cu" signal "L5")
		(12 "In5.Cu" signal "L6VCC")
		(14 "In6.Cu" signal "L7VCC")
		(16 "In7.Cu" signal "L8")
		(18 "In8.Cu" signal "L9GND")
		(20 "In9.Cu" signal "L10")
		(22 "In10.Cu" signal "L11GND")
		(2 "B.Cu" signal "BOTTOM")
		(9 "F.Adhes" user "F.Adhesive")
		(11 "B.Adhes" user "B.Adhesive")
		(13 "F.Paste" user "Package Geometry/Pastemask Top")
		(15 "B.Paste" user "Package Geometry/Pastemask Bottom")
		(5 "F.SilkS" user "Ref Des/Silkscreen Top")
		(7 "B.SilkS" user "Ref Des/Silkscreen Bottom")
		(1 "F.Mask" user "Board Geometry/Soldermask Top")
		(3 "B.Mask" user "Board Geometry/Soldermask Bottom")
		(17 "Dwgs.User" user "User.Drawings")
		(19 "Cmts.User" user "User.Comments")
		(21 "Eco1.User" user "User.Eco1")
		(23 "Eco2.User" user "User.Eco2")
		(25 "Edge.Cuts" user "Board Geometry/Outline")
		(27 "Margin" user)
		(31 "F.CrtYd" user "Package Geometry/Place Bound Top")
		(29 "B.CrtYd" user "Package Geometry/Place Bound Bottom")
		(35 "F.Fab" user "Ref Des/Assembly Top")
		(33 "B.Fab" user "Ref Des/Assembly Bottom")
	)
	(footprint ""
		(layer "F.Cu")
		(at 141.548866 -131.656074)
		(property "Reference" "R1055"
			(at 0 0 0)
			(layer "F.SilkS")
			(hide yes)
			(effects
				(font
					(size 1.27 1.27)
				)
			)
		)
		(property "Value" "3K83R2F-GP"
			(at 0.064008 -3.993896 0)
			(unlocked yes)
			(layer "F.Fab")
			(hide yes)
			(effects
				(font
					(size 1.016 1.016)
					(thickness 0.1524)
				)
			)
		)
		(property "Device Type" "R402H16"
			(at 0.064008 -5.517896 0)
			(unlocked yes)
			(layer "F.Fab")
			(hide yes)
			(effects
				(font
					(size 1.016 1.016)
					(thickness 0.1524)
				)
			)
		)
		(duplicate_pad_numbers_are_jumpers no)
		(fp_line
			(start -0.508 -0.9398)
			(end -0.508 0.9398)
			(stroke
				(width 0.1524)
				(type default)
			)
			(layer "F.SilkS")
		)
		(fp_line
			(start 0.508 -0.9398)
			(end -0.508 -0.9398)
			(stroke
				(width 0.1524)
				(type default)
			)
			(layer "F.SilkS")
		)
		(fp_rect
			(start -0.508 0.9398)
			(end 0.508 -0.9398)
			(stroke
				(width 0)
				(type default)
			)
			(fill no)
			(layer "F.CrtYd")
		)
		(fp_rect
			(start -0.508 0.9398)
			(end 0.508 -0.9398)
			(stroke
				(width 0)
				(type default)
			)
			(fill no)
			(layer "F.Fab")
		)
		(pad "1" smd custom
			(at 0 -0.4445)
			(size 0.1397 0.1397)
			(layers "F.Cu" "F.Mask" "F.Paste")
			(net "COMP_A_PGOOD")
			(options
				(clearance outline)
				(anchor circle)
			)
			(primitives
				(gr_poly
					(pts
						(arc
							(start -0.1778 -0.2794)
							(mid -0.249642 -0.249642)
							(end -0.2794 -0.1778)
						)
						(arc
							(start -0.2794 0.1778)
							(mid -0.249642 0.249642)
							(end -0.1778 0.2794)
						)
						(arc
							(start 0.1778 0.2794)
							(mid 0.249642 0.249642)
							(end 0.2794 0.1778)
						)
						(arc
							(start 0.2794 -0.1778)
							(mid 0.249642 -0.249642)
							(end 0.1778 -0.2794)
						)
					)
					(width 0)
					(fill yes)
				)
			)
		)
		(pad "2" smd custom
			(at 0 0.4445)
			(size 0.1397 0.1397)
			(layers "F.Cu" "F.Mask" "F.Paste")
			(net "GND")
			(options
				(clearance outline)
				(anchor circle)
			)
			(primitives
				(gr_poly
					(pts
						(arc
							(start -0.1778 -0.2794)
							(mid -0.249642 -0.249642)
							(end -0.2794 -0.1778)
						)
						(arc
							(start -0.2794 0.1778)
							(mid -0.249642 0.249642)
							(end -0.1778 0.2794)
						)
						(arc
							(start 0.1778 0.2794)
							(mid 0.249642 0.249642)
							(end 0.2794 0.1778)
						)
						(arc
							(start 0.2794 -0.1778)
							(mid 0.249642 -0.249642)
							(end 0.1778 -0.2794)
						)
					)
					(width 0)
					(fill yes)
				)
			)
		)
	)
	(footprint ""
		(layer "F.Cu")
		(at 477.739202 -43.939968 90)
		(property "Reference" "VIA16"
			(at 0 0 90)
			(layer "F.SilkS")
			(hide yes)
			(effects
				(font
					(size 1.27 1.27)
				)
			)
		)
		(property "Value" "100OHM-8L-1D6MM-L18L16-GP"
			(at -3.7211 -4.5085 90)
			(unlocked yes)
			(layer "F.Fab")
			(hide yes)
			(effects
				(font
					(size 1.016 1.016)
					(thickness 0.1524)
				)
			)
		)
		(property "Device Type" "VIA-PCIE-4P-394076"
			(at -3.7211 -6.0325 90)
			(unlocked yes)
			(layer "F.Fab")
			(hide yes)
			(effects
				(font
					(size 1.016 1.016)
					(thickness 0.1524)
				)
			)
		)
		(duplicate_pad_numbers_are_jumpers no)
		(fp_rect
			(start -1.9685 0.381)
			(end 1.9685 -0.381)
			(stroke
				(width 0)
				(type default)
			)
			(fill no)
			(layer "F.CrtYd")
		)
		(fp_rect
			(start -1.9685 0.381)
			(end 1.9685 -0.381)
			(stroke
				(width 0)
				(type default)
			)
			(fill no)
			(layer "F.Fab")
		)
		(pad "1" thru_hole circle
			(at -1.5875 0 90)
			(size 0.508 0.508)
			(drill 0.254)
			(layers "*.Cu" "*.Mask")
			(remove_unused_layers no)
			(net "GND")
			(clearance 0.127)
			(thermal_gap 0.127)
		)
		(pad "2" thru_hole circle
			(at -0.5715 0 90)
			(size 0.508 0.508)
			(drill 0.254)
			(layers "*.Cu" "*.Mask")
			(remove_unused_layers no)
			(net "PHY_SCC_A_TO_DRV_A_35_DP")
			(clearance 0.127)
			(thermal_gap 0.127)
		)
		(pad "3" thru_hole circle
			(at 0.5715 0 90)
			(size 0.508 0.508)
			(drill 0.254)
			(layers "*.Cu" "*.Mask")
			(remove_unused_layers no)
			(net "PHY_SCC_A_TO_DRV_A_35_DN")
			(clearance 0.127)
			(thermal_gap 0.127)
		)
		(pad "4" thru_hole circle
			(at 1.5875 0 90)
			(size 0.508 0.508)
			(drill 0.254)
			(layers "*.Cu" "*.Mask")
			(remove_unused_layers no)
			(net "GND")
			(clearance 0.127)
			(thermal_gap 0.127)
		)
	)
	(footprint ""
		(layer "F.Cu")
		(at 132.581396 -285.260542 180)
		(property "Reference" "Q18"
			(at 0 0 180)
			(layer "F.SilkS")
			(hide yes)
			(effects
				(font
					(size 1.27 1.27)
				)
			)
		)
		(property "Value" "AO4406AL-GP"
			(at -3.707384 -1.5367 180)
			(unlocked yes)
			(layer "F.Fab")
			(hide yes)
			(effects
				(font
					(size 1.016 1.016)
					(thickness 0.1524)
				)
			)
		)
		(property "Device Type" "SOIC8H69"
			(at -3.707384 -3.0607 180)
			(unlocked yes)
			(layer "F.Fab")
			(hide yes)
			(effects
				(font
					(size 1.016 1.016)
					(thickness 0.1524)
				)
			)
		)
		(duplicate_pad_numbers_are_jumpers no)
		(fp_line
			(start 2.1336 1.4224)
			(end 2.1336 -1.4224)
			(stroke
				(width 0.1524)
				(type default)
			)
			(layer "F.SilkS")
		)
		(fp_line
			(start 2.1336 -1.4224)
			(end -2.7432 -1.4224)
			(stroke
				(width 0.1524)
				(type default)
			)
			(layer "F.SilkS")
		)
		(fp_line
			(start -2.1844 -0.0508)
			(end -2.7178 0.508)
			(stroke
				(width 0.1524)
				(type default)
			)
			(layer "F.SilkS")
		)
		(fp_line
			(start -2.6289 3.4417)
			(end -2.6289 1.4732)
			(stroke
				(width 0.381)
				(type default)
			)
			(layer "F.SilkS")
		)
		(fp_line
			(start -2.7178 -0.508)
			(end -2.1844 -0.0508)
			(stroke
				(width 0.1524)
				(type default)
			)
			(layer "F.SilkS")
		)
		(fp_line
			(start -2.7432 1.4224)
			(end 2.1336 1.4224)
			(stroke
				(width 0.1524)
				(type default)
			)
			(layer "F.SilkS")
		)
		(fp_line
			(start -2.7432 1.4224)
			(end -2.6416 1.4224)
			(stroke
				(width 0.1524)
				(type default)
			)
			(layer "F.SilkS")
		)
		(fp_line
			(start -2.7432 -1.4224)
			(end -2.7432 1.4224)
			(stroke
				(width 0.1524)
				(type default)
			)
			(layer "F.SilkS")
		)
		(fp_poly
			(pts
				(xy -2.2098 -1.4224) (xy -2.2098 1.4224) (xy 2.2098 1.4224) (xy 2.2098 -1.4224)
			)
			(stroke
				(width 0)
				(type default)
			)
			(fill yes)
			(layer "F.SilkS")
		)
		(fp_rect
			(start -2.450084 2.999994)
			(end 2.450084 -2.999994)
			(stroke
				(width 0)
				(type default)
			)
			(fill no)
			(layer "F.CrtYd")
		)
		(fp_poly
			(pts
				(xy -2.8194 3.6322) (xy -2.8194 -3.6322) (xy 2.8194 -3.6322) (xy 2.8194 1.18364) (xy 2.450084 1.18364)
				(xy 2.450084 -2.999994) (xy -2.450084 -2.999994) (xy -2.450084 2.999994) (xy 2.450084 2.999994)
				(xy 2.450084 1.18618) (xy 2.8194 1.18618) (xy 2.8194 3.6322)
			)
			(stroke
				(width 0)
				(type default)
			)
			(fill no)
			(layer "F.CrtYd")
		)
		(fp_rect
			(start -2.8194 3.6322)
			(end 2.8194 -3.6322)
			(stroke
				(width 0)
				(type default)
			)
			(fill no)
			(layer "F.Fab")
		)
		(pad "1" smd rect
			(at -1.905 2.54 180)
			(size 0.635 1.651)
			(layers "F.Cu" "F.Mask" "F.Paste")
			(net "P5V_HDD3")
		)
		(pad "2" smd rect
			(at -0.635 2.54 180)
			(size 0.635 1.651)
			(layers "F.Cu" "F.Mask" "F.Paste")
			(net "P5V_HDD3")
		)
		(pad "3" smd rect
			(at 0.635 2.54 180)
			(size 0.635 1.651)
			(layers "F.Cu" "F.Mask" "F.Paste")
			(net "P5V_HDD3")
		)
		(pad "4" smd rect
			(at 1.905 2.54 180)
			(size 0.635 1.651)
			(layers "F.Cu" "F.Mask" "F.Paste")
			(net "SW_HDD_P3")
		)
		(pad "5" smd rect
			(at 1.905 -2.54 180)
			(size 0.635 1.651)
			(layers "F.Cu" "F.Mask" "F.Paste")
			(net "P5V_A_1")
		)
		(pad "6" smd rect
			(at 0.635 -2.54 180)
			(size 0.635 1.651)
			(layers "F.Cu" "F.Mask" "F.Paste")
			(net "P5V_A_1")
		)
		(pad "7" smd rect
			(at -0.635 -2.54 180)
			(size 0.635 1.651)
			(layers "F.Cu" "F.Mask" "F.Paste")
			(net "P5V_A_1")
		)
		(pad "8" smd rect
			(at -1.905 -2.54 180)
			(size 0.635 1.651)
			(layers "F.Cu" "F.Mask" "F.Paste")
			(net "P5V_A_1")
		)
	)
	(footprint ""
		(layer "F.Cu")
		(at 87.340948 -189.462918 180)
		(property "Reference" "C229"
			(at 0 0 180)
			(layer "F.SilkS")
			(hide yes)
			(effects
				(font
					(size 1.27 1.27)
				)
			)
		)
		(property "Value" "SC1U25V3KX-GP"
			(at 0 -2.8194 180)
			(unlocked yes)
			(layer "F.Fab")
			(hide yes)
			(effects
				(font
					(size 1.016 1.016)
					(thickness 0.1524)
				)
			)
		)
		(property "Device Type" "C603H36"
			(at 0 -4.3434 180)
			(unlocked yes)
			(layer "F.Fab")
			(hide yes)
			(effects
				(font
					(size 1.016 1.016)
					(thickness 0.1524)
				)
			)
		)
		(duplicate_pad_numbers_are_jumpers no)
		(fp_line
			(start 0.508 0)
			(end -0.508 0)
			(stroke
				(width 0.2032)
				(type default)
			)
			(layer "F.SilkS")
		)
		(fp_rect
			(start -0.5842 1.3335)
			(end 0.5842 -1.3335)
			(stroke
				(width 0)
				(type default)
			)
			(fill no)
			(layer "F.CrtYd")
		)
		(fp_rect
			(start -0.5842 1.3335)
			(end 0.5842 -1.3335)
			(stroke
				(width 0)
				(type default)
			)
			(fill no)
			(layer "F.Fab")
		)
		(pad "1" smd custom
			(at 0 -0.762 180)
			(size 0.2159 0.2159)
			(layers "F.Cu" "F.Mask" "F.Paste")
			(net "P12V_HDD14")
			(options
				(clearance outline)
				(anchor circle)
			)
			(primitives
				(gr_poly
					(pts
						(arc
							(start -0.3302 -0.4318)
							(mid -0.402042 -0.402042)
							(end -0.4318 -0.3302)
						)
						(arc
							(start -0.4318 0.3302)
							(mid -0.402042 0.402042)
							(end -0.3302 0.4318)
						)
						(arc
							(start 0.3302 0.4318)
							(mid 0.402042 0.402042)
							(end 0.4318 0.3302)
						)
						(arc
							(start 0.4318 -0.3302)
							(mid 0.402042 -0.402042)
							(end 0.3302 -0.4318)
						)
					)
					(width 0)
					(fill yes)
				)
			)
		)
		(pad "2" smd custom
			(at 0 0.762 180)
			(size 0.2159 0.2159)
			(layers "F.Cu" "F.Mask" "F.Paste")
			(net "GND")
			(options
				(clearance outline)
				(anchor circle)
			)
			(primitives
				(gr_poly
					(pts
						(arc
							(start -0.3302 -0.4318)
							(mid -0.402042 -0.402042)
							(end -0.4318 -0.3302)
						)
						(arc
							(start -0.4318 0.3302)
							(mid -0.402042 0.402042)
							(end -0.3302 0.4318)
						)
						(arc
							(start 0.3302 0.4318)
							(mid 0.402042 0.402042)
							(end 0.4318 0.3302)
						)
						(arc
							(start 0.4318 -0.3302)
							(mid 0.402042 -0.402042)
							(end 0.3302 -0.4318)
						)
					)
					(width 0)
					(fill yes)
				)
			)
		)
	)
	(footprint ""
		(layer "F.Cu")
		(at 244.094 -387.9088)
		(property "Reference" "C610"
			(at 0 0 0)
			(layer "F.SilkS")
			(hide yes)
			(effects
				(font
					(size 1.27 1.27)
				)
			)
		)
		(property "Value" "SCD015U25V2KX-GP"
			(at 1.1811 -2.7051 0)
			(unlocked yes)
			(layer "F.Fab")
			(hide yes)
			(effects
				(font
					(size 1.016 1.016)
					(thickness 0.1524)
				)
			)
		)
		(property "Device Type" "C402H22"
			(at 1.1811 -4.2291 0)
			(unlocked yes)
			(layer "F.Fab")
			(hide yes)
			(effects
				(font
					(size 1.016 1.016)
					(thickness 0.1524)
				)
			)
		)
		(duplicate_pad_numbers_are_jumpers no)
		(fp_rect
			(start -0.4318 0.9525)
			(end 0.4318 -0.9525)
			(stroke
				(width 0)
				(type default)
			)
			(fill no)
			(layer "F.CrtYd")
		)
		(fp_rect
			(start -0.4318 0.9525)
			(end 0.4318 -0.9525)
			(stroke
				(width 0)
				(type default)
			)
			(fill no)
			(layer "F.Fab")
		)
		(pad "1" smd custom
			(at 0 -0.4445)
			(size 0.1524 0.1524)
			(layers "F.Cu" "F.Mask" "F.Paste")
			(net "MB3_HS_SENSE_P")
			(options
				(clearance outline)
				(anchor circle)
			)
			(primitives
				(gr_poly
					(pts
						(arc
							(start 0.3048 -0.2032)
							(mid 0.275042 -0.275042)
							(end 0.2032 -0.3048)
						)
						(arc
							(start -0.2032 -0.3048)
							(mid -0.275042 -0.275042)
							(end -0.3048 -0.2032)
						)
						(arc
							(start -0.3048 0.2032)
							(mid -0.275042 0.275042)
							(end -0.2032 0.3048)
						)
						(arc
							(start 0.2032 0.3048)
							(mid 0.275042 0.275042)
							(end 0.3048 0.2032)
						)
					)
					(width 0)
					(fill yes)
				)
			)
		)
		(pad "2" smd custom
			(at 0 0.4445)
			(size 0.1524 0.1524)
			(layers "F.Cu" "F.Mask" "F.Paste")
			(net "MB3_HS_SENSE_N")
			(options
				(clearance outline)
				(anchor circle)
			)
			(primitives
				(gr_poly
					(pts
						(arc
							(start 0.3048 -0.2032)
							(mid 0.275042 -0.275042)
							(end 0.2032 -0.3048)
						)
						(arc
							(start -0.2032 -0.3048)
							(mid -0.275042 -0.275042)
							(end -0.3048 -0.2032)
						)
						(arc
							(start -0.3048 0.2032)
							(mid -0.275042 0.275042)
							(end -0.2032 0.3048)
						)
						(arc
							(start 0.2032 0.3048)
							(mid 0.275042 0.275042)
							(end 0.3048 0.2032)
						)
					)
					(width 0)
					(fill yes)
				)
			)
		)
	)
	(footprint ""
		(layer "F.Cu")
		(at 178.181 -292.778942 -90)
		(property "Reference" "C105"
			(at 0 0 270)
			(layer "F.SilkS")
			(hide yes)
			(effects
				(font
					(size 1.27 1.27)
				)
			)
		)
		(property "Value" "SC1U16V3KX-5GP"
			(at 0 -2.8194 270)
			(unlocked yes)
			(layer "F.Fab")
			(hide yes)
			(effects
				(font
					(size 1.016 1.016)
					(thickness 0.1524)
				)
			)
		)
		(property "Device Type" "C603H36"
			(at 0 -4.3434 270)
			(unlocked yes)
			(layer "F.Fab")
			(hide yes)
			(effects
				(font
					(size 1.016 1.016)
					(thickness 0.1524)
				)
			)
		)
		(duplicate_pad_numbers_are_jumpers no)
		(fp_line
			(start 0.508 0)
			(end -0.508 0)
			(stroke
				(width 0.2032)
				(type default)
			)
			(layer "F.SilkS")
		)
		(fp_rect
			(start -0.5842 1.3335)
			(end 0.5842 -1.3335)
			(stroke
				(width 0)
				(type default)
			)
			(fill no)
			(layer "F.CrtYd")
		)
		(fp_rect
			(start -0.5842 1.3335)
			(end 0.5842 -1.3335)
			(stroke
				(width 0)
				(type default)
			)
			(fill no)
			(layer "F.Fab")
		)
		(pad "1" smd custom
			(at 0 -0.762 270)
			(size 0.2159 0.2159)
			(layers "F.Cu" "F.Mask" "F.Paste")
			(net "P5V_HDD5")
			(options
				(clearance outline)
				(anchor circle)
			)
			(primitives
				(gr_poly
					(pts
						(arc
							(start -0.3302 -0.4318)
							(mid -0.402042 -0.402042)
							(end -0.4318 -0.3302)
						)
						(arc
							(start -0.4318 0.3302)
							(mid -0.402042 0.402042)
							(end -0.3302 0.4318)
						)
						(arc
							(start 0.3302 0.4318)
							(mid 0.402042 0.402042)
							(end 0.4318 0.3302)
						)
						(arc
							(start 0.4318 -0.3302)
							(mid 0.402042 -0.402042)
							(end 0.3302 -0.4318)
						)
					)
					(width 0)
					(fill yes)
				)
			)
		)
		(pad "2" smd custom
			(at 0 0.762 270)
			(size 0.2159 0.2159)
			(layers "F.Cu" "F.Mask" "F.Paste")
			(net "GND")
			(options
				(clearance outline)
				(anchor circle)
			)
			(primitives
				(gr_poly
					(pts
						(arc
							(start -0.3302 -0.4318)
							(mid -0.402042 -0.402042)
							(end -0.4318 -0.3302)
						)
						(arc
							(start -0.4318 0.3302)
							(mid -0.402042 0.402042)
							(end -0.3302 0.4318)
						)
						(arc
							(start 0.3302 0.4318)
							(mid 0.402042 0.402042)
							(end 0.4318 0.3302)
						)
						(arc
							(start 0.4318 -0.3302)
							(mid 0.402042 -0.402042)
							(end 0.3302 -0.4318)
						)
					)
					(width 0)
					(fill yes)
				)
			)
		)
	)
)
